FILE_TYPE = MULTI_PHYS_TABLE;

PART 'PI3EQX1002EZREX'

{========================================================================================}
:VALUE             | PART_TYPE | MATERIAL | PART_NUMBER    = STANDARD    | LIFECYCLE      | PART_NUMBER   | JEDEC_TYPE               | DESCRIPTION                            | MANUFTR | MANUF_PN          | RD_CMPLS_LVL | CMPLS_LVL | FROM_PJ   | CLASS | DIP_SMD | DATA                      | EE_CHECK_LIST | FP_ECN                | PSL | CREATOR | STATUS | MSD | ESD_CDM | ESD_HBM | ESD_MM | PIN_LENGTH_SHORT_PIN | PIN_LENGTH_LONG_PIN | CREATEDAY  ;
{========================================================================================}
 'PI3EQX1002EZREX' | 'SMLF'    | 'IC'     | 'AL001002007'(!) = ''               | ''               | 'AL001002007' |'TQFN24_TH_0-35_2-5X2-5'| 'IC OTHERS(24P) PI3EQX1002EZREX(TQFN)' | 'DDS'   | 'PI3EQX1002EZREX' | 'EP(V1)'     | 'EP(V1)'  | 'F0T-KEN' | 'IC'  | ''      | 'DDS_PI3EQX1002EZREX.pdf' | ''            | 'PI3EQX1002EZREX.msg' | ''  | ''      | ''     | ''  | ''      | ''      | ''     | '0 MILS'             | '0 MILS'            | '20211208'
 'PI3EQX1002EZREX' | 'SMLF'    | 'EMPTY'  | 'AL001002007'(!) = ''               | ''               | 'AL001002007' |'TQFN24_TH_0-35_2-5X2-5'| 'IC OTHERS(24P) PI3EQX1002EZREX(TQFN)' | 'DDS'   | 'PI3EQX1002EZREX' | 'EP(V1)'     | 'EP(V1)'  | 'F0T-KEN' | 'IC'  | ''      | 'DDS_PI3EQX1002EZREX.pdf' | ''            | 'PI3EQX1002EZREX.msg' | ''  | ''      | ''     | ''  | ''      | ''      | ''     | '0 MILS'             | '0 MILS'            | '20211208'

END_PART

END.

